# T6G (Grand Teton) — schematic netlist excerpt (pin names and nets, part order shuffled) for the footprints in the layout excerpt that follows; sources: Cadence DE-HDL packaged netlist, KiCad conversion of 04192023_DAF0TMB3IC0_F0TG_MB_C_brd_V02_OCP.brd

R2936  Q_RES  100K 1% EMPTY  pkg 0402LF  page 130 : A = P3V3_AUX ; B = FM_GPU_PWR_EN_R
PC2262  Q_CAP  22UF 16V 20% X6S  pkg C0805  page 190 : A = SW_P3V3_AUX_FLT ; B = GND
PC147_IOP0_1  Q_CAP  2.2UF 10V 10% X6S  pkg C0402  page 205 : A = PVDDCR_CPU1_P0_PVCC ; B = GND

(kicad_pcb
	(version 20260206)
	(generator "pcbnew")
	(generator_version "10.0")
	(general
		(thickness 1.6)
		(legacy_teardrops no)
	)
	(paper "A4")
	(title_block
		(title "04192023_DAF0TMB3IC0_F0TG_MB_C_brd_V02_OCP.brd")
		(comment 1 "Grand Teton / footprints 90-92 of 8354")
	)
	(layers
		(0 "F.Cu" signal "TOP")
		(4 "In1.Cu" signal "GND")
		(6 "In2.Cu" signal "IN1")
		(8 "In3.Cu" signal "GND1")
		(10 "In4.Cu" signal "IN2")
		(12 "In5.Cu" signal "GND2")
		(14 "In6.Cu" signal "IN3")
		(16 "In7.Cu" signal "GND3")
		(18 "In8.Cu" signal "VCC")
		(20 "In9.Cu" signal "VCC1")
		(22 "In10.Cu" signal "GND4")
		(24 "In11.Cu" signal "IN4")
		(26 "In12.Cu" signal "GND5")
		(28 "In13.Cu" signal "IN5")
		(30 "In14.Cu" signal "GND6")
		(32 "In15.Cu" signal "IN6")
		(34 "In16.Cu" signal "GND7")
		(2 "B.Cu" signal "BOTTOM")
		(9 "F.Adhes" user "F.Adhesive")
		(11 "B.Adhes" user "B.Adhesive")
		(13 "F.Paste" user "Package Geometry/Pastemask Top")
		(15 "B.Paste" user "Package Geometry/Pastemask Bottom")
		(5 "F.SilkS" user "Ref Des/Silkscreen Top")
		(7 "B.SilkS" user "Ref Des/Silkscreen Bottom")
		(1 "F.Mask" user "Board Geometry/Soldermask Top")
		(3 "B.Mask" user "Board Geometry/Soldermask Bottom")
		(17 "Dwgs.User" user "User.Drawings")
		(19 "Cmts.User" user "User.Comments")
		(21 "Eco1.User" user "User.Eco1")
		(23 "Eco2.User" user "User.Eco2")
		(25 "Edge.Cuts" user "Board Geometry/Outline")
		(27 "Margin" user)
		(31 "F.CrtYd" user "Package Geometry/Place Bound Top")
		(29 "B.CrtYd" user "Package Geometry/Place Bound Bottom")
		(35 "F.Fab" user "Ref Des/Assembly Top")
		(33 "B.Fab" user "Ref Des/Assembly Bottom")
	)
	(footprint ""
		(layer "F.Cu")
		(at 444.700152 -47.522384 -90)
		(property "Reference" "PC2262"
			(at 0 0 270)
			(layer "F.SilkS")
			(hide yes)
			(effects
				(font
					(size 1.27 1.27)
				)
			)
		)
		(property "Value" ""
			(at 0 0 270)
			(layer "F.Fab")
			(effects
				(font
					(size 1.27 1.27)
				)
			)
		)
		(duplicate_pad_numbers_are_jumpers no)
		(fp_line
			(start -1.524 0.762)
			(end -1.524 -0.762)
			(stroke
				(width 0.1524)
				(type default)
			)
			(layer "F.SilkS")
		)
		(fp_line
			(start 1.524 0.762)
			(end -1.524 0.762)
			(stroke
				(width 0.1524)
				(type default)
			)
			(layer "F.SilkS")
		)
		(fp_line
			(start -1.524 -0.762)
			(end 1.524 -0.762)
			(stroke
				(width 0.1524)
				(type default)
			)
			(layer "F.SilkS")
		)
		(fp_line
			(start 1.524 -0.762)
			(end 1.524 0.762)
			(stroke
				(width 0.1524)
				(type default)
			)
			(layer "F.SilkS")
		)
		(fp_line
			(start -1.1049 0.724916)
			(end 1.1049 0.724916)
			(stroke
				(width 0.1)
				(type default)
			)
			(layer "F.Fab")
		)
		(fp_line
			(start 1.1049 0.724916)
			(end 1.1049 -0.724916)
			(stroke
				(width 0.1)
				(type default)
			)
			(layer "F.Fab")
		)
		(fp_line
			(start -1.1049 -0.724916)
			(end -1.1049 0.724916)
			(stroke
				(width 0.1)
				(type default)
			)
			(layer "F.Fab")
		)
		(fp_line
			(start 1.1049 -0.724916)
			(end -1.1049 -0.724916)
			(stroke
				(width 0.1)
				(type default)
			)
			(layer "F.Fab")
		)
		(pad "1" smd rect
			(at -0.889 0 90)
			(size 1.016 1.27)
			(layers "F.Cu" "F.Mask" "F.Paste")
			(net "SW_P3V3_AUX_FLT")
		)
		(pad "2" smd rect
			(at 0.889 0 90)
			(size 1.016 1.27)
			(layers "F.Cu" "F.Mask" "F.Paste")
			(net "GND")
		)
	)
	(footprint ""
		(layer "F.Cu")
		(at 296.681906 -346.714572 -90)
		(property "Reference" "PC147_IOP0_1"
			(at 0 0 270)
			(layer "F.SilkS")
			(hide yes)
			(effects
				(font
					(size 1.27 1.27)
				)
			)
		)
		(property "Value" ""
			(at 0 0 270)
			(layer "F.Fab")
			(effects
				(font
					(size 1.27 1.27)
				)
			)
		)
		(duplicate_pad_numbers_are_jumpers no)
		(fp_line
			(start -0.7874 0.4064)
			(end -0.7874 -0.4064)
			(stroke
				(width 0.1524)
				(type default)
			)
			(layer "F.SilkS")
		)
		(fp_line
			(start 0.7874 0.4064)
			(end -0.7874 0.4064)
			(stroke
				(width 0.1524)
				(type default)
			)
			(layer "F.SilkS")
		)
		(fp_line
			(start -0.7874 -0.4064)
			(end 0.7874 -0.4064)
			(stroke
				(width 0.1524)
				(type default)
			)
			(layer "F.SilkS")
		)
		(fp_line
			(start 0.7874 -0.4064)
			(end 0.7874 0.4064)
			(stroke
				(width 0.1524)
				(type default)
			)
			(layer "F.SilkS")
		)
		(fp_line
			(start -0.67945 0.3048)
			(end -0.67945 -0.305054)
			(stroke
				(width 0.1)
				(type default)
			)
			(layer "F.Fab")
		)
		(fp_line
			(start -0.12065 0.3048)
			(end -0.67945 0.3048)
			(stroke
				(width 0.1)
				(type default)
			)
			(layer "F.Fab")
		)
		(fp_line
			(start 0.120396 0.3048)
			(end 0.120396 0.2794)
			(stroke
				(width 0.1)
				(type default)
			)
			(layer "F.Fab")
		)
		(fp_line
			(start 0.67945 0.3048)
			(end 0.120396 0.3048)
			(stroke
				(width 0.1)
				(type default)
			)
			(layer "F.Fab")
		)
		(fp_line
			(start -0.12065 0.2794)
			(end -0.12065 0.3048)
			(stroke
				(width 0.1)
				(type default)
			)
			(layer "F.Fab")
		)
		(fp_line
			(start 0.120396 0.2794)
			(end -0.12065 0.2794)
			(stroke
				(width 0.1)
				(type default)
			)
			(layer "F.Fab")
		)
		(fp_line
			(start -0.12065 -0.2794)
			(end 0.12065 -0.2794)
			(stroke
				(width 0.1)
				(type default)
			)
			(layer "F.Fab")
		)
		(fp_line
			(start 0.12065 -0.2794)
			(end 0.12065 -0.3048)
			(stroke
				(width 0.1)
				(type default)
			)
			(layer "F.Fab")
		)
		(fp_line
			(start 0.12065 -0.3048)
			(end 0.67945 -0.3048)
			(stroke
				(width 0.1)
				(type default)
			)
			(layer "F.Fab")
		)
		(fp_line
			(start 0.67945 -0.3048)
			(end 0.67945 0.3048)
			(stroke
				(width 0.1)
				(type default)
			)
			(layer "F.Fab")
		)
		(fp_line
			(start -0.67945 -0.305054)
			(end -0.12065 -0.305054)
			(stroke
				(width 0.1)
				(type default)
			)
			(layer "F.Fab")
		)
		(fp_line
			(start -0.12065 -0.305054)
			(end -0.12065 -0.2794)
			(stroke
				(width 0.1)
				(type default)
			)
			(layer "F.Fab")
		)
		(pad "1" smd circle
			(at -0.40005 0 270)
			(size 0 0)
			(layers "F.Cu" "F.Mask" "F.Paste")
			(net "PVDDCR_CPU1_P0_PVCC")
		)
		(pad "2" smd circle
			(at 0.40005 0 270)
			(size 0 0)
			(layers "F.Cu" "F.Mask" "F.Paste")
			(net "GND")
		)
	)
	(footprint ""
		(layer "F.Cu")
		(at 44.069 -437.134)
		(property "Reference" "R2936"
			(at 0 0 0)
			(layer "F.SilkS")
			(hide yes)
			(effects
				(font
					(size 1.27 1.27)
				)
			)
		)
		(property "Value" ""
			(at 0 0 0)
			(layer "F.Fab")
			(effects
				(font
					(size 1.27 1.27)
				)
			)
		)
		(duplicate_pad_numbers_are_jumpers no)
		(fp_line
			(start -0.7874 -0.4064)
			(end 0.7874 -0.4064)
			(stroke
				(width 0.1524)
				(type default)
			)
			(layer "F.SilkS")
		)
		(fp_line
			(start -0.7874 0.4064)
			(end -0.7874 -0.4064)
			(stroke
				(width 0.1524)
				(type default)
			)
			(layer "F.SilkS")
		)
		(fp_line
			(start 0.7874 -0.4064)
			(end 0.7874 0.4064)
			(stroke
				(width 0.1524)
				(type default)
			)
			(layer "F.SilkS")
		)
		(fp_line
			(start 0.7874 0.4064)
			(end -0.7874 0.4064)
			(stroke
				(width 0.1524)
				(type default)
			)
			(layer "F.SilkS")
		)
		(fp_line
			(start -0.67945 -0.305054)
			(end -0.12065 -0.305054)
			(stroke
				(width 0.1)
				(type default)
			)
			(layer "F.Fab")
		)
		(fp_line
			(start -0.67945 0.3048)
			(end -0.67945 -0.305054)
			(stroke
				(width 0.1)
				(type default)
			)
			(layer "F.Fab")
		)
		(fp_line
			(start -0.12065 -0.305054)
			(end -0.12065 -0.2794)
			(stroke
				(width 0.1)
				(type default)
			)
			(layer "F.Fab")
		)
		(fp_line
			(start -0.12065 -0.2794)
			(end 0.12065 -0.2794)
			(stroke
				(width 0.1)
				(type default)
			)
			(layer "F.Fab")
		)
		(fp_line
			(start -0.12065 0.2794)
			(end -0.12065 0.3048)
			(stroke
				(width 0.1)
				(type default)
			)
			(layer "F.Fab")
		)
		(fp_line
			(start -0.12065 0.3048)
			(end -0.67945 0.3048)
			(stroke
				(width 0.1)
				(type default)
			)
			(layer "F.Fab")
		)
		(fp_line
			(start 0.120396 0.2794)
			(end -0.12065 0.2794)
			(stroke
				(width 0.1)
				(type default)
			)
			(layer "F.Fab")
		)
		(fp_line
			(start 0.120396 0.3048)
			(end 0.120396 0.2794)
			(stroke
				(width 0.1)
				(type default)
			)
			(layer "F.Fab")
		)
		(fp_line
			(start 0.12065 -0.3048)
			(end 0.67945 -0.3048)
			(stroke
				(width 0.1)
				(type default)
			)
			(layer "F.Fab")
		)
		(fp_line
			(start 0.12065 -0.2794)
			(end 0.12065 -0.3048)
			(stroke
				(width 0.1)
				(type default)
			)
			(layer "F.Fab")
		)
		(fp_line
			(start 0.67945 -0.3048)
			(end 0.67945 0.3048)
			(stroke
				(width 0.1)
				(type default)
			)
			(layer "F.Fab")
		)
		(fp_line
			(start 0.67945 0.3048)
			(end 0.120396 0.3048)
			(stroke
				(width 0.1)
				(type default)
			)
			(layer "F.Fab")
		)
		(pad "1" smd circle
			(at -0.40005 0)
			(size 0 0)
			(layers "F.Cu" "F.Mask" "F.Paste")
			(net "P3V3_AUX")
		)
		(pad "2" smd circle
			(at 0.40005 0)
			(size 0 0)
			(layers "F.Cu" "F.Mask" "F.Paste")
			(net "FM_GPU_PWR_EN_R")
		)
	)
)
